# S9S_MB_2U (Grand Teton) — schematic netlist excerpt (pin names and nets, part order shuffled) for the footprints in the layout excerpt that follows; sources: Cadence DE-HDL packaged netlist, KiCad conversion of 03242023_DA0F0TMBIJ0_F0T_Motherboard_J_brd_V01_OCP.brd

R993  Q_RES  33.2 1% CHIP  pkg 0402LF  page 236 : A = SMB_S3M_CPU0_SCL ; B = SMB_S3M_CPU0_R_SCL
C639  Q_CAP  0.1UF 25V 10% X7R  pkg 0402  page 154 : A = P3V3_AUX ; B = GND

(kicad_pcb
	(version 20260206)
	(generator "pcbnew")
	(generator_version "10.0")
	(general
		(thickness 1.6)
		(legacy_teardrops no)
	)
	(paper "A4")
	(title_block
		(title "03242023_DA0F0TMBIJ0_F0T_Motherboard_J_brd_V01_OCP.brd")
		(comment 1 "Grand Teton / footprints 3885-3886 of 6105")
	)
	(layers
		(0 "F.Cu" signal "TOP")
		(4 "In1.Cu" signal "GND")
		(6 "In2.Cu" signal "IN1")
		(8 "In3.Cu" signal "GND1")
		(10 "In4.Cu" signal "IN2")
		(12 "In5.Cu" signal "GND2")
		(14 "In6.Cu" signal "IN3")
		(16 "In7.Cu" signal "GND3")
		(18 "In8.Cu" signal "VCC")
		(20 "In9.Cu" signal "VCC1")
		(22 "In10.Cu" signal "GND4")
		(24 "In11.Cu" signal "IN4")
		(26 "In12.Cu" signal "GND5")
		(28 "In13.Cu" signal "IN5")
		(30 "In14.Cu" signal "GND6")
		(32 "In15.Cu" signal "IN6")
		(34 "In16.Cu" signal "GND7")
		(2 "B.Cu" signal "BOTTOM")
		(9 "F.Adhes" user "F.Adhesive")
		(11 "B.Adhes" user "B.Adhesive")
		(13 "F.Paste" user "Package Geometry/Pastemask Top")
		(15 "B.Paste" user "Package Geometry/Pastemask Bottom")
		(5 "F.SilkS" user "Ref Des/Silkscreen Top")
		(7 "B.SilkS" user "Ref Des/Silkscreen Bottom")
		(1 "F.Mask" user "Board Geometry/Soldermask Top")
		(3 "B.Mask" user "Board Geometry/Soldermask Bottom")
		(17 "Dwgs.User" user "User.Drawings")
		(19 "Cmts.User" user "User.Comments")
		(21 "Eco1.User" user "User.Eco1")
		(23 "Eco2.User" user "User.Eco2")
		(25 "Edge.Cuts" user "Board Geometry/Outline")
		(27 "Margin" user)
		(31 "F.CrtYd" user "Package Geometry/Place Bound Top")
		(29 "B.CrtYd" user "Package Geometry/Place Bound Bottom")
		(35 "F.Fab" user "Ref Des/Assembly Top")
		(33 "B.Fab" user "Ref Des/Assembly Bottom")
	)
	(footprint ""
		(layer "F.Cu")
		(at 461.916526 -100.470208)
		(property "Reference" "C639"
			(at 0 0 0)
			(layer "F.SilkS")
			(hide yes)
			(effects
				(font
					(size 1.27 1.27)
				)
			)
		)
		(property "Value" ""
			(at 0 0 0)
			(layer "F.Fab")
			(effects
				(font
					(size 1.27 1.27)
				)
			)
		)
		(duplicate_pad_numbers_are_jumpers no)
		(fp_line
			(start -0.7874 -0.4064)
			(end 0.7874 -0.4064)
			(stroke
				(width 0.1524)
				(type default)
			)
			(layer "F.SilkS")
		)
		(fp_line
			(start -0.7874 0.4064)
			(end -0.7874 -0.4064)
			(stroke
				(width 0.1524)
				(type default)
			)
			(layer "F.SilkS")
		)
		(fp_line
			(start 0.7874 -0.4064)
			(end 0.7874 0.4064)
			(stroke
				(width 0.1524)
				(type default)
			)
			(layer "F.SilkS")
		)
		(fp_line
			(start 0.7874 0.4064)
			(end -0.7874 0.4064)
			(stroke
				(width 0.1524)
				(type default)
			)
			(layer "F.SilkS")
		)
		(fp_line
			(start -0.67945 -0.305054)
			(end -0.12065 -0.305054)
			(stroke
				(width 0.1)
				(type default)
			)
			(layer "F.Fab")
		)
		(fp_line
			(start -0.67945 0.3048)
			(end -0.67945 -0.305054)
			(stroke
				(width 0.1)
				(type default)
			)
			(layer "F.Fab")
		)
		(fp_line
			(start -0.12065 -0.305054)
			(end -0.12065 -0.2794)
			(stroke
				(width 0.1)
				(type default)
			)
			(layer "F.Fab")
		)
		(fp_line
			(start -0.12065 -0.2794)
			(end 0.12065 -0.2794)
			(stroke
				(width 0.1)
				(type default)
			)
			(layer "F.Fab")
		)
		(fp_line
			(start -0.12065 0.2794)
			(end -0.12065 0.3048)
			(stroke
				(width 0.1)
				(type default)
			)
			(layer "F.Fab")
		)
		(fp_line
			(start -0.12065 0.3048)
			(end -0.67945 0.3048)
			(stroke
				(width 0.1)
				(type default)
			)
			(layer "F.Fab")
		)
		(fp_line
			(start 0.120396 0.2794)
			(end -0.12065 0.2794)
			(stroke
				(width 0.1)
				(type default)
			)
			(layer "F.Fab")
		)
		(fp_line
			(start 0.120396 0.3048)
			(end 0.120396 0.2794)
			(stroke
				(width 0.1)
				(type default)
			)
			(layer "F.Fab")
		)
		(fp_line
			(start 0.12065 -0.3048)
			(end 0.67945 -0.3048)
			(stroke
				(width 0.1)
				(type default)
			)
			(layer "F.Fab")
		)
		(fp_line
			(start 0.12065 -0.2794)
			(end 0.12065 -0.3048)
			(stroke
				(width 0.1)
				(type default)
			)
			(layer "F.Fab")
		)
		(fp_line
			(start 0.67945 -0.3048)
			(end 0.67945 0.3048)
			(stroke
				(width 0.1)
				(type default)
			)
			(layer "F.Fab")
		)
		(fp_line
			(start 0.67945 0.3048)
			(end 0.120396 0.3048)
			(stroke
				(width 0.1)
				(type default)
			)
			(layer "F.Fab")
		)
		(pad "1" smd circle
			(at -0.40005 0)
			(size 0 0)
			(layers "F.Cu" "F.Mask" "F.Paste")
			(net "P3V3_AUX")
		)
		(pad "2" smd circle
			(at 0.40005 0)
			(size 0 0)
			(layers "F.Cu" "F.Mask" "F.Paste")
			(net "GND")
		)
	)
	(footprint ""
		(layer "F.Cu")
		(at 393.741148 -162.360864 -90)
		(property "Reference" "R993"
			(at 0 0 270)
			(layer "F.SilkS")
			(hide yes)
			(effects
				(font
					(size 1.27 1.27)
				)
			)
		)
		(property "Value" ""
			(at 0 0 270)
			(layer "F.Fab")
			(effects
				(font
					(size 1.27 1.27)
				)
			)
		)
		(duplicate_pad_numbers_are_jumpers no)
		(fp_line
			(start -0.7874 0.4064)
			(end -0.7874 -0.4064)
			(stroke
				(width 0.1524)
				(type default)
			)
			(layer "F.SilkS")
		)
		(fp_line
			(start 0.7874 0.4064)
			(end -0.7874 0.4064)
			(stroke
				(width 0.1524)
				(type default)
			)
			(layer "F.SilkS")
		)
		(fp_line
			(start -0.7874 -0.4064)
			(end 0.7874 -0.4064)
			(stroke
				(width 0.1524)
				(type default)
			)
			(layer "F.SilkS")
		)
		(fp_line
			(start 0.7874 -0.4064)
			(end 0.7874 0.4064)
			(stroke
				(width 0.1524)
				(type default)
			)
			(layer "F.SilkS")
		)
		(fp_line
			(start -0.67945 0.3048)
			(end -0.67945 -0.305054)
			(stroke
				(width 0.1)
				(type default)
			)
			(layer "F.Fab")
		)
		(fp_line
			(start -0.12065 0.3048)
			(end -0.67945 0.3048)
			(stroke
				(width 0.1)
				(type default)
			)
			(layer "F.Fab")
		)
		(fp_line
			(start 0.120396 0.3048)
			(end 0.120396 0.2794)
			(stroke
				(width 0.1)
				(type default)
			)
			(layer "F.Fab")
		)
		(fp_line
			(start 0.67945 0.3048)
			(end 0.120396 0.3048)
			(stroke
				(width 0.1)
				(type default)
			)
			(layer "F.Fab")
		)
		(fp_line
			(start -0.12065 0.2794)
			(end -0.12065 0.3048)
			(stroke
				(width 0.1)
				(type default)
			)
			(layer "F.Fab")
		)
		(fp_line
			(start 0.120396 0.2794)
			(end -0.12065 0.2794)
			(stroke
				(width 0.1)
				(type default)
			)
			(layer "F.Fab")
		)
		(fp_line
			(start -0.12065 -0.2794)
			(end 0.12065 -0.2794)
			(stroke
				(width 0.1)
				(type default)
			)
			(layer "F.Fab")
		)
		(fp_line
			(start 0.12065 -0.2794)
			(end 0.12065 -0.3048)
			(stroke
				(width 0.1)
				(type default)
			)
			(layer "F.Fab")
		)
		(fp_line
			(start 0.12065 -0.3048)
			(end 0.67945 -0.3048)
			(stroke
				(width 0.1)
				(type default)
			)
			(layer "F.Fab")
		)
		(fp_line
			(start 0.67945 -0.3048)
			(end 0.67945 0.3048)
			(stroke
				(width 0.1)
				(type default)
			)
			(layer "F.Fab")
		)
		(fp_line
			(start -0.67945 -0.305054)
			(end -0.12065 -0.305054)
			(stroke
				(width 0.1)
				(type default)
			)
			(layer "F.Fab")
		)
		(fp_line
			(start -0.12065 -0.305054)
			(end -0.12065 -0.2794)
			(stroke
				(width 0.1)
				(type default)
			)
			(layer "F.Fab")
		)
		(pad "1" smd circle
			(at -0.40005 0 270)
			(size 0 0)
			(layers "F.Cu" "F.Mask" "F.Paste")
			(net "SMB_S3M_CPU0_SCL")
		)
		(pad "2" smd circle
			(at 0.40005 0 270)
			(size 0 0)
			(layers "F.Cu" "F.Mask" "F.Paste")
			(net "SMB_S3M_CPU0_R_SCL")
		)
	)
)
